(kicad_pcb
	(version 20241229)
	(generator "pcbnew")
	(generator_version "9.0")
	(general
		(thickness 1.59)
		(legacy_teardrops no)
	)
	(paper "A3")
	(title_block
		(title "usb-c-power-adapter")
		(date "2025-06-24")
		(rev "1.1.2")
		(company "Antmicro")
		(comment 9 "footprints 9-14 of 122")
	)
	(layers
		(0 "F.Cu" signal)
		(4 "In1.Cu" signal)
		(6 "In2.Cu" signal)
		(2 "B.Cu" signal)
		(9 "F.Adhes" user "F.Adhesive")
		(11 "B.Adhes" user "B.Adhesive")
		(13 "F.Paste" user)
		(15 "B.Paste" user)
		(5 "F.SilkS" user "F.Silkscreen")
		(7 "B.SilkS" user "B.Silkscreen")
		(1 "F.Mask" user)
		(3 "B.Mask" user)
		(17 "Dwgs.User" user "User.Drawings")
		(19 "Cmts.User" user "User.Comments")
		(21 "Eco1.User" user "User.Eco1")
		(23 "Eco2.User" user "User.Eco2")
		(25 "Edge.Cuts" user)
		(27 "Margin" user)
		(31 "F.CrtYd" user "F.Courtyard")
		(29 "B.CrtYd" user "B.Courtyard")
		(35 "F.Fab" user)
		(33 "B.Fab" user)
	)
	(footprint "antmicro-footprints:R_0402_1005Metric"
		(layer "F.Cu")
		(at 98.1 89 -90)
		(descr "Resistor SMD 0402")
		(tags "resistor SMD 0402")
		(property "Reference" "R12"
			(at 1.8 2.5 90)
			(layer "F.SilkS")
			(effects
				(font
					(size 0.7 0.7)
					(thickness 0.15)
				)
				(justify left bottom)
			)
		)
		(property "Value" "R_0R_0402"
			(at -1.011843 1.772047 90)
			(layer "F.Fab")
			(effects
				(font
					(size 0.7 0.7)
					(thickness 0.15)
				)
				(justify right bottom)
			)
		)
		(property "Datasheet" "https://industrial.panasonic.com/cdbs/www-data/pdf/RDA0000/AOA0000C301.pdf"
			(at 0 0 270)
			(layer "F.Fab")
			(hide yes)
			(effects
				(font
					(size 1.27 1.27)
					(thickness 0.15)
				)
			)
		)
		(property "Description" "SMD Chip Resistor, Jumper, 0 ohm, 100 mW, 0402 [1005 Metric], Thick Film, General Purpose"
			(at 0 0 270)
			(layer "F.Fab")
			(hide yes)
			(effects
				(font
					(size 1.27 1.27)
					(thickness 0.15)
				)
			)
		)
		(property "Manufacturer" "Panasonic"
			(at 0 0 270)
			(unlocked yes)
			(layer "F.Fab")
			(hide yes)
			(effects
				(font
					(size 1 1)
					(thickness 0.15)
				)
			)
		)
		(property "MPN" "ERJ2GE0R00X"
			(at 0 0 270)
			(unlocked yes)
			(layer "F.Fab")
			(hide yes)
			(effects
				(font
					(size 1 1)
					(thickness 0.15)
				)
			)
		)
		(property "Val" "0R"
			(at 0 0 270)
			(unlocked yes)
			(layer "F.Fab")
			(hide yes)
			(effects
				(font
					(size 1 1)
					(thickness 0.15)
				)
			)
		)
		(property "License" "Apache-2.0"
			(at 0 0 270)
			(unlocked yes)
			(layer "F.Fab")
			(hide yes)
			(effects
				(font
					(size 1 1)
					(thickness 0.15)
				)
			)
		)
		(property "Author" "Antmicro"
			(at 0 0 270)
			(unlocked yes)
			(layer "F.Fab")
			(hide yes)
			(effects
				(font
					(size 1 1)
					(thickness 0.15)
				)
			)
		)
		(property "Tolerance" ""
			(at 0 0 270)
			(unlocked yes)
			(layer "F.Fab")
			(hide yes)
			(effects
				(font
					(size 1 1)
					(thickness 0.15)
				)
			)
		)
		(property "Current" "1A"
			(at 0 0 270)
			(unlocked yes)
			(layer "F.Fab")
			(hide yes)
			(effects
				(font
					(size 1 1)
					(thickness 0.15)
				)
			)
		)
		(sheetname "/DC-DC Converters/")
		(sheetfile "dc-dc_converters.kicad_sch")
		(attr smd)
		(fp_rect
			(start -0.925 -0.47)
			(end 0.925 0.47)
			(stroke
				(width 0.05)
				(type default)
			)
			(fill no)
			(layer "F.CrtYd")
		)
		(fp_rect
			(start -0.5 -0.25)
			(end 0.5 0.25)
			(stroke
				(width 0.15)
				(type solid)
			)
			(fill no)
			(layer "F.Fab")
		)
		(pad "1" smd roundrect
			(at -0.48 0 270)
			(size 0.59 0.64)
			(layers "F.Cu" "F.Mask" "F.Paste")
			(roundrect_rratio 0.25)
			(net 18 "Net-(U2-V_{SNS})")
			(pintype "passive")
		)
		(pad "2" smd roundrect
			(at 0.48 0 270)
			(size 0.59 0.64)
			(layers "F.Cu" "F.Mask" "F.Paste")
			(roundrect_rratio 0.25)
			(net 5 "+12V")
			(pintype "passive")
		)
	)
	(footprint "antmicro-footprints:C_0402_1005Metric"
		(layer "F.Cu")
		(at 99.05 89 -90)
		(descr "Capacitor SMD 0402")
		(tags "capacitor SMD 0402")
		(property "Reference" "C12"
			(at 1.8 2.45 90)
			(layer "F.SilkS")
			(effects
				(font
					(size 0.7 0.7)
					(thickness 0.15)
				)
				(justify left bottom)
			)
		)
		(property "Value" "C_1n2_50V_0402"
			(at -1.022927 2.155213 90)
			(layer "F.Fab")
			(effects
				(font
					(size 0.7 0.7)
					(thickness 0.15)
				)
				(justify right bottom)
			)
		)
		(property "Datasheet" "https://www.murata.com/products/productdetail?partno=GCM155R71H122KA37%23"
			(at 0 0 270)
			(layer "F.Fab")
			(hide yes)
			(effects
				(font
					(size 1.27 1.27)
					(thickness 0.15)
				)
			)
		)
		(property "Description" "SMD Multilayer Ceramic Capacitor, 1200 pF, 50 V, 0402 [1005 Metric], ± 10%, X7R, GCM"
			(at 0 0 270)
			(layer "F.Fab")
			(hide yes)
			(effects
				(font
					(size 1.27 1.27)
					(thickness 0.15)
				)
			)
		)
		(property "Manufacturer" "Murata"
			(at 0 0 270)
			(unlocked yes)
			(layer "F.Fab")
			(hide yes)
			(effects
				(font
					(size 1 1)
					(thickness 0.15)
				)
			)
		)
		(property "MPN" "GCM155R71H122KA37D"
			(at 0 0 270)
			(unlocked yes)
			(layer "F.Fab")
			(hide yes)
			(effects
				(font
					(size 1 1)
					(thickness 0.15)
				)
			)
		)
		(property "Val" "1n2"
			(at 0 0 270)
			(unlocked yes)
			(layer "F.Fab")
			(hide yes)
			(effects
				(font
					(size 1 1)
					(thickness 0.15)
				)
			)
		)
		(property "License" "Apache-2.0"
			(at 0 0 270)
			(unlocked yes)
			(layer "F.Fab")
			(hide yes)
			(effects
				(font
					(size 1 1)
					(thickness 0.15)
				)
			)
		)
		(property "Author" "Antmicro"
			(at 0 0 270)
			(unlocked yes)
			(layer "F.Fab")
			(hide yes)
			(effects
				(font
					(size 1 1)
					(thickness 0.15)
				)
			)
		)
		(property "Voltage" "50V"
			(at 0 0 270)
			(unlocked yes)
			(layer "F.Fab")
			(hide yes)
			(effects
				(font
					(size 1 1)
					(thickness 0.15)
				)
			)
		)
		(property "Dielectric" ""
			(at 0 0 270)
			(unlocked yes)
			(layer "F.Fab")
			(hide yes)
			(effects
				(font
					(size 1 1)
					(thickness 0.15)
				)
			)
		)
		(sheetname "/DC-DC Converters/")
		(sheetfile "dc-dc_converters.kicad_sch")
		(attr smd exclude_from_pos_files exclude_from_bom dnp)
		(fp_rect
			(start -0.925 -0.47)
			(end 0.925 0.47)
			(stroke
				(width 0.05)
				(type default)
			)
			(fill no)
			(layer "F.CrtYd")
		)
		(fp_line
			(start -0.494 0.248)
			(end -0.494 -0.25)
			(stroke
				(width 0.15)
				(type solid)
			)
			(layer "F.Fab")
		)
		(fp_line
			(start 0.504 0.248)
			(end -0.494 0.248)
			(stroke
				(width 0.15)
				(type solid)
			)
			(layer "F.Fab")
		)
		(fp_line
			(start -0.494 -0.25)
			(end 0.504 -0.25)
			(stroke
				(width 0.15)
				(type solid)
			)
			(layer "F.Fab")
		)
		(fp_line
			(start 0.504 -0.25)
			(end 0.504 0.248)
			(stroke
				(width 0.15)
				(type solid)
			)
			(layer "F.Fab")
		)
		(pad "1" smd roundrect
			(at -0.48 0 270)
			(size 0.59 0.64)
			(layers "F.Cu" "F.Mask" "F.Paste")
			(roundrect_rratio 0.25)
			(net 18 "Net-(U2-V_{SNS})")
			(pintype "passive")
		)
		(pad "2" smd roundrect
			(at 0.48 0 270)
			(size 0.59 0.64)
			(layers "F.Cu" "F.Mask" "F.Paste")
			(roundrect_rratio 0.25)
			(net 19 "/DC-DC Converters/12V_SNS")
			(pintype "passive")
		)
	)
	(footprint "antmicro-footprints:C_0402_1005Metric"
		(layer "F.Cu")
		(at 97.1 89 -90)
		(descr "Capacitor SMD 0402")
		(tags "capacitor SMD 0402")
		(property "Reference" "C5"
			(at 1.8 2.5 90)
			(layer "F.SilkS")
			(effects
				(font
					(size 0.7 0.7)
					(thickness 0.15)
				)
				(justify left bottom)
			)
		)
		(property "Value" "C_33n_0402"
			(at -1.022927 2.155213 90)
			(layer "F.Fab")
			(effects
				(font
					(size 0.7 0.7)
					(thickness 0.15)
				)
				(justify right bottom)
			)
		)
		(property "Datasheet" "https://www.murata.com/products/productdetail?partno=GCM155R71E333KA55%23"
			(at 0 0 270)
			(layer "F.Fab")
			(hide yes)
			(effects
				(font
					(size 1.27 1.27)
					(thickness 0.15)
				)
			)
		)
		(property "Description" "SMD Multilayer Ceramic Capacitor, 33000 pF, 25 V, 0402 [1005 Metric], ± 10%, X7R, MC"
			(at 0 0 270)
			(layer "F.Fab")
			(hide yes)
			(effects
				(font
					(size 1.27 1.27)
					(thickness 0.15)
				)
			)
		)
		(property "Manufacturer" "Murata"
			(at 0 0 270)
			(unlocked yes)
			(layer "F.Fab")
			(hide yes)
			(effects
				(font
					(size 1 1)
					(thickness 0.15)
				)
			)
		)
		(property "MPN" "GCM155R71E333KA55D"
			(at 0 0 270)
			(unlocked yes)
			(layer "F.Fab")
			(hide yes)
			(effects
				(font
					(size 1 1)
					(thickness 0.15)
				)
			)
		)
		(property "Val" "33n"
			(at 0 0 270)
			(unlocked yes)
			(layer "F.Fab")
			(hide yes)
			(effects
				(font
					(size 1 1)
					(thickness 0.15)
				)
			)
		)
		(property "License" "Apache-2.0"
			(at 0 0 270)
			(unlocked yes)
			(layer "F.Fab")
			(hide yes)
			(effects
				(font
					(size 1 1)
					(thickness 0.15)
				)
			)
		)
		(property "Author" "Antmicro"
			(at 0 0 270)
			(unlocked yes)
			(layer "F.Fab")
			(hide yes)
			(effects
				(font
					(size 1 1)
					(thickness 0.15)
				)
			)
		)
		(property "Voltage" ""
			(at 0 0 270)
			(unlocked yes)
			(layer "F.Fab")
			(hide yes)
			(effects
				(font
					(size 1 1)
					(thickness 0.15)
				)
			)
		)
		(property "Dielectric" ""
			(at 0 0 270)
			(unlocked yes)
			(layer "F.Fab")
			(hide yes)
			(effects
				(font
					(size 1 1)
					(thickness 0.15)
				)
			)
		)
		(sheetname "/DC-DC Converters/")
		(sheetfile "dc-dc_converters.kicad_sch")
		(attr smd)
		(fp_rect
			(start -0.925 -0.47)
			(end 0.925 0.47)
			(stroke
				(width 0.05)
				(type default)
			)
			(fill no)
			(layer "F.CrtYd")
		)
		(fp_line
			(start -0.494 0.248)
			(end -0.494 -0.25)
			(stroke
				(width 0.15)
				(type solid)
			)
			(layer "F.Fab")
		)
		(fp_line
			(start 0.504 0.248)
			(end -0.494 0.248)
			(stroke
				(width 0.15)
				(type solid)
			)
			(layer "F.Fab")
		)
		(fp_line
			(start -0.494 -0.25)
			(end 0.504 -0.25)
			(stroke
				(width 0.15)
				(type solid)
			)
			(layer "F.Fab")
		)
		(fp_line
			(start 0.504 -0.25)
			(end 0.504 0.248)
			(stroke
				(width 0.15)
				(type solid)
			)
			(layer "F.Fab")
		)
		(pad "1" smd roundrect
			(at -0.48 0 270)
			(size 0.59 0.64)
			(layers "F.Cu" "F.Mask" "F.Paste")
			(roundrect_rratio 0.25)
			(net 13 "/DC-DC Converters/12V_SS")
			(pintype "passive")
		)
		(pad "2" smd roundrect
			(at 0.48 0 270)
			(size 0.59 0.64)
			(layers "F.Cu" "F.Mask" "F.Paste")
			(roundrect_rratio 0.25)
			(net 2 "GND")
			(pintype "passive")
		)
	)
	(footprint "antmicro-footprints:R_0402_1005Metric"
		(layer "F.Cu")
		(at 97.8 80.3 90)
		(descr "Resistor SMD 0402")
		(tags "resistor SMD 0402")
		(property "Reference" "R5"
			(at -3.8819 5.0514 180)
			(layer "B.SilkS")
			(effects
				(font
					(size 0.7 0.7)
					(thickness 0.15)
				)
				(justify left bottom mirror)
			)
		)
		(property "Value" "R_2k_0402"
			(at -1.011843 1.772047 90)
			(layer "F.Fab")
			(effects
				(font
					(size 0.7 0.7)
					(thickness 0.15)
				)
				(justify left bottom)
			)
		)
		(property "Datasheet" "https://www.bourns.com/docs/product-datasheets/cr.pdf"
			(at 0 0 90)
			(layer "F.Fab")
			(hide yes)
			(effects
				(font
					(size 1.27 1.27)
					(thickness 0.15)
				)
			)
		)
		(property "Description" "SMD Chip Resistor, 2 kohm, ± 1%, 62.5 mW, 0402 [1005 Metric], Thick Film, General Purpose"
			(at 0 0 90)
			(layer "F.Fab")
			(hide yes)
			(effects
				(font
					(size 1.27 1.27)
					(thickness 0.15)
				)
			)
		)
		(property "Manufacturer" "Bourns"
			(at 0 0 90)
			(unlocked yes)
			(layer "F.Fab")
			(hide yes)
			(effects
				(font
					(size 1 1)
					(thickness 0.15)
				)
			)
		)
		(property "MPN" "CR0402-FX-2001GLF"
			(at 0 0 90)
			(unlocked yes)
			(layer "F.Fab")
			(hide yes)
			(effects
				(font
					(size 1 1)
					(thickness 0.15)
				)
			)
		)
		(property "Val" "2k"
			(at 0 0 90)
			(unlocked yes)
			(layer "F.Fab")
			(hide yes)
			(effects
				(font
					(size 1 1)
					(thickness 0.15)
				)
			)
		)
		(property "License" "Apache-2.0"
			(at 0 0 90)
			(unlocked yes)
			(layer "F.Fab")
			(hide yes)
			(effects
				(font
					(size 1 1)
					(thickness 0.15)
				)
			)
		)
		(property "Author" "Antmicro"
			(at 0 0 90)
			(unlocked yes)
			(layer "F.Fab")
			(hide yes)
			(effects
				(font
					(size 1 1)
					(thickness 0.15)
				)
			)
		)
		(property "Tolerance" "1%"
			(at 0 0 90)
			(unlocked yes)
			(layer "F.Fab")
			(hide yes)
			(effects
				(font
					(size 1 1)
					(thickness 0.15)
				)
			)
		)
		(sheetname "/DC-DC Converters/")
		(sheetfile "dc-dc_converters.kicad_sch")
		(attr smd)
		(fp_rect
			(start -0.925 -0.47)
			(end 0.925 0.47)
			(stroke
				(width 0.05)
				(type default)
			)
			(fill no)
			(layer "F.CrtYd")
		)
		(fp_rect
			(start -0.5 -0.25)
			(end 0.5 0.25)
			(stroke
				(width 0.15)
				(type solid)
			)
			(fill no)
			(layer "F.Fab")
		)
		(pad "1" smd roundrect
			(at -0.48 0 90)
			(size 0.59 0.64)
			(layers "F.Cu" "F.Mask" "F.Paste")
			(roundrect_rratio 0.25)
			(net 43 "/DC-DC Converters/12V_MODE")
			(pintype "passive")
		)
		(pad "2" smd roundrect
			(at 0.48 0 90)
			(size 0.59 0.64)
			(layers "F.Cu" "F.Mask" "F.Paste")
			(roundrect_rratio 0.25)
			(net 2 "GND")
			(pintype "passive")
		)
	)
	(footprint "antmicro-footprints:C_0402_1005Metric"
		(layer "F.Cu")
		(at 91.5 81.8 -90)
		(descr "Capacitor SMD 0402")
		(tags "capacitor SMD 0402")
		(property "Reference" "C6"
			(at -1.8 -0.5 0)
			(layer "F.SilkS")
			(effects
				(font
					(size 0.7 0.7)
					(thickness 0.15)
				)
				(justify right bottom)
			)
		)
		(property "Value" "C_100n_50V_X8L_0402"
			(at -1.022927 2.155213 90)
			(layer "F.Fab")
			(effects
				(font
					(size 0.7 0.7)
					(thickness 0.15)
				)
				(justify right bottom)
			)
		)
		(property "Datasheet" "https://www.murata.com/products/productdetail?partno=GCM155L8EH104KE07%23"
			(at 0 0 270)
			(layer "F.Fab")
			(hide yes)
			(effects
				(font
					(size 1.27 1.27)
					(thickness 0.15)
				)
			)
		)
		(property "Description" "SMD Multilayer Ceramic Capacitor, 100nF, 50V, 0402, ±10%, X8L"
			(at 0 0 270)
			(layer "F.Fab")
			(hide yes)
			(effects
				(font
					(size 1.27 1.27)
					(thickness 0.15)
				)
			)
		)
		(property "MPN" "GCM155L8EH104KE07D"
			(at 0 0 270)
			(unlocked yes)
			(layer "F.Fab")
			(hide yes)
			(effects
				(font
					(size 1 1)
					(thickness 0.15)
				)
			)
		)
		(property "Val" "100n"
			(at 0 0 270)
			(unlocked yes)
			(layer "F.Fab")
			(hide yes)
			(effects
				(font
					(size 1 1)
					(thickness 0.15)
				)
			)
		)
		(property "Voltage" "50V"
			(at 0 0 270)
			(unlocked yes)
			(layer "F.Fab")
			(hide yes)
			(effects
				(font
					(size 1 1)
					(thickness 0.15)
				)
			)
		)
		(property "Dielectric" "X8L"
			(at 0 0 270)
			(unlocked yes)
			(layer "F.Fab")
			(hide yes)
			(effects
				(font
					(size 1 1)
					(thickness 0.15)
				)
			)
		)
		(property "Manufacturer" "Murata"
			(at 0 0 270)
			(unlocked yes)
			(layer "F.Fab")
			(hide yes)
			(effects
				(font
					(size 1 1)
					(thickness 0.15)
				)
			)
		)
		(property "License" "Apache-2.0"
			(at 0 0 270)
			(unlocked yes)
			(layer "F.Fab")
			(hide yes)
			(effects
				(font
					(size 1 1)
					(thickness 0.15)
				)
			)
		)
		(property "Author" "Antmicro"
			(at 0 0 270)
			(unlocked yes)
			(layer "F.Fab")
			(hide yes)
			(effects
				(font
					(size 1 1)
					(thickness 0.15)
				)
			)
		)
		(sheetname "/DC-DC Converters/")
		(sheetfile "dc-dc_converters.kicad_sch")
		(attr smd)
		(fp_rect
			(start -0.925 -0.47)
			(end 0.925 0.47)
			(stroke
				(width 0.05)
				(type default)
			)
			(fill no)
			(layer "F.CrtYd")
		)
		(fp_line
			(start -0.494 0.248)
			(end -0.494 -0.25)
			(stroke
				(width 0.15)
				(type solid)
			)
			(layer "F.Fab")
		)
		(fp_line
			(start 0.504 0.248)
			(end -0.494 0.248)
			(stroke
				(width 0.15)
				(type solid)
			)
			(layer "F.Fab")
		)
		(fp_line
			(start -0.494 -0.25)
			(end 0.504 -0.25)
			(stroke
				(width 0.15)
				(type solid)
			)
			(layer "F.Fab")
		)
		(fp_line
			(start 0.504 -0.25)
			(end 0.504 0.248)
			(stroke
				(width 0.15)
				(type solid)
			)
			(layer "F.Fab")
		)
		(pad "1" smd roundrect
			(at -0.48 0 270)
			(size 0.59 0.64)
			(layers "F.Cu" "F.Mask" "F.Paste")
			(roundrect_rratio 0.25)
			(net 2 "GND")
			(pintype "passive")
		)
		(pad "2" smd roundrect
			(at 0.48 0 270)
			(size 0.59 0.64)
			(layers "F.Cu" "F.Mask" "F.Paste")
			(roundrect_rratio 0.25)
			(net 12 "Net-(U2-V_{CIN})")
			(pintype "passive")
		)
	)
	(footprint "antmicro-footprints:C_0402_1005Metric"
		(layer "F.Cu")
		(at 100.25 87.6 180)
		(descr "Capacitor SMD 0402")
		(tags "capacitor SMD 0402")
		(property "Reference" "C13"
			(at -0.842 -0.538 0)
			(layer "F.SilkS")
			(effects
				(font
					(size 0.7 0.7)
					(thickness 0.15)
				)
				(justify left bottom)
			)
		)
		(property "Value" "C_270p_25V_0402"
			(at -1.022927 2.155213 0)
			(layer "F.Fab")
			(effects
				(font
					(size 0.7 0.7)
					(thickness 0.15)
				)
				(justify right bottom)
			)
		)
		(property "Datasheet" "https://www.kemet.com/en/us/capacitors/product/C0402C271J3GAC7867.html"
			(at 0 0 180)
			(layer "F.Fab")
			(hide yes)
			(effects
				(font
					(size 1.27 1.27)
					(thickness 0.15)
				)
			)
		)
		(property "Description" "SMD Multilayer Ceramic Capacitor, 270 pF, 25 V, 0402 [1005 Metric], ± 5%, C0G / NP0"
			(at 0 0 180)
			(layer "F.Fab")
			(hide yes)
			(effects
				(font
					(size 1.27 1.27)
					(thickness 0.15)
				)
			)
		)
		(property "Manufacturer" "KEMET"
			(at 0 0 180)
			(unlocked yes)
			(layer "F.Fab")
			(hide yes)
			(effects
				(font
					(size 1 1)
					(thickness 0.15)
				)
			)
		)
		(property "MPN" "C0402C271J3GAC7867"
			(at 0 0 180)
			(unlocked yes)
			(layer "F.Fab")
			(hide yes)
			(effects
				(font
					(size 1 1)
					(thickness 0.15)
				)
			)
		)
		(property "Val" "270p"
			(at 0 0 180)
			(unlocked yes)
			(layer "F.Fab")
			(hide yes)
			(effects
				(font
					(size 1 1)
					(thickness 0.15)
				)
			)
		)
		(property "License" "Apache-2.0"
			(at 0 0 180)
			(unlocked yes)
			(layer "F.Fab")
			(hide yes)
			(effects
				(font
					(size 1 1)
					(thickness 0.15)
				)
			)
		)
		(property "Author" "Antmicro"
			(at 0 0 180)
			(unlocked yes)
			(layer "F.Fab")
			(hide yes)
			(effects
				(font
					(size 1 1)
					(thickness 0.15)
				)
			)
		)
		(property "Voltage" "25V"
			(at 0 0 180)
			(unlocked yes)
			(layer "F.Fab")
			(hide yes)
			(effects
				(font
					(size 1 1)
					(thickness 0.15)
				)
			)
		)
		(property "Dielectric" ""
			(at 0 0 180)
			(unlocked yes)
			(layer "F.Fab")
			(hide yes)
			(effects
				(font
					(size 1 1)
					(thickness 0.15)
				)
			)
		)
		(sheetname "/DC-DC Converters/")
		(sheetfile "dc-dc_converters.kicad_sch")
		(attr smd exclude_from_pos_files exclude_from_bom dnp)
		(fp_rect
			(start -0.925 -0.47)
			(end 0.925 0.47)
			(stroke
				(width 0.05)
				(type default)
			)
			(fill no)
			(layer "F.CrtYd")
		)
		(fp_line
			(start 0.504 0.248)
			(end -0.494 0.248)
			(stroke
				(width 0.15)
				(type solid)
			)
			(layer "F.Fab")
		)
		(fp_line
			(start 0.504 -0.25)
			(end 0.504 0.248)
			(stroke
				(width 0.15)
				(type solid)
			)
			(layer "F.Fab")
		)
		(fp_line
			(start -0.494 0.248)
			(end -0.494 -0.25)
			(stroke
				(width 0.15)
				(type solid)
			)
			(layer "F.Fab")
		)
		(fp_line
			(start -0.494 -0.25)
			(end 0.504 -0.25)
			(stroke
				(width 0.15)
				(type solid)
			)
			(layer "F.Fab")
		)
		(pad "1" smd roundrect
			(at -0.48 0 180)
			(size 0.59 0.64)
			(layers "F.Cu" "F.Mask" "F.Paste")
			(roundrect_rratio 0.25)
			(net 4 "Net-(C13-Pad1)")
			(pintype "passive")
		)
		(pad "2" smd roundrect
			(at 0.48 0 180)
			(size 0.59 0.64)
			(layers "F.Cu" "F.Mask" "F.Paste")
			(roundrect_rratio 0.25)
			(net 2 "GND")
			(pintype "passive")
		)
	)
)
